# S9S_MB_2U (Grand Teton) — schematic netlist excerpt (pin names and nets, part order shuffled) for the footprints in the layout excerpt that follows; sources: Cadence DE-HDL packaged netlist, KiCad conversion of 03242023_DA0F0TMBIJ0_F0T_Motherboard_J_brd_V01_OCP.brd

R1934  Q_RES  33.2 1% CHIP  pkg 0402LF  page 45 : A = SMB_S3M_CPU1_PIROM_3V3AUX_SCL ; B = SMB_S3M_CPU1_PIROM_3V3AUX_SCL_1

(kicad_pcb
	(version 20260206)
	(generator "pcbnew")
	(generator_version "10.0")
	(general
		(thickness 1.6)
		(legacy_teardrops no)
	)
	(paper "A4")
	(title_block
		(title "03242023_DA0F0TMBIJ0_F0T_Motherboard_J_brd_V01_OCP.brd")
		(comment 1 "Grand Teton / footprints 4536-4536 of 6105")
	)
	(layers
		(0 "F.Cu" signal "TOP")
		(4 "In1.Cu" signal "GND")
		(6 "In2.Cu" signal "IN1")
		(8 "In3.Cu" signal "GND1")
		(10 "In4.Cu" signal "IN2")
		(12 "In5.Cu" signal "GND2")
		(14 "In6.Cu" signal "IN3")
		(16 "In7.Cu" signal "GND3")
		(18 "In8.Cu" signal "VCC")
		(20 "In9.Cu" signal "VCC1")
		(22 "In10.Cu" signal "GND4")
		(24 "In11.Cu" signal "IN4")
		(26 "In12.Cu" signal "GND5")
		(28 "In13.Cu" signal "IN5")
		(30 "In14.Cu" signal "GND6")
		(32 "In15.Cu" signal "IN6")
		(34 "In16.Cu" signal "GND7")
		(2 "B.Cu" signal "BOTTOM")
		(9 "F.Adhes" user "F.Adhesive")
		(11 "B.Adhes" user "B.Adhesive")
		(13 "F.Paste" user "Package Geometry/Pastemask Top")
		(15 "B.Paste" user "Package Geometry/Pastemask Bottom")
		(5 "F.SilkS" user "Ref Des/Silkscreen Top")
		(7 "B.SilkS" user "Ref Des/Silkscreen Bottom")
		(1 "F.Mask" user "Board Geometry/Soldermask Top")
		(3 "B.Mask" user "Board Geometry/Soldermask Bottom")
		(17 "Dwgs.User" user "User.Drawings")
		(19 "Cmts.User" user "User.Comments")
		(21 "Eco1.User" user "User.Eco1")
		(23 "Eco2.User" user "User.Eco2")
		(25 "Edge.Cuts" user "Board Geometry/Outline")
		(27 "Margin" user)
		(31 "F.CrtYd" user "Package Geometry/Place Bound Top")
		(29 "B.CrtYd" user "Package Geometry/Place Bound Bottom")
		(35 "F.Fab" user "Ref Des/Assembly Top")
		(33 "B.Fab" user "Ref Des/Assembly Bottom")
	)
	(footprint ""
		(layer "B.Cu")
		(at 178.61788 -329.479148)
		(property "Reference" "R1934"
			(at 0 0 0)
			(layer "B.SilkS")
			(hide yes)
			(effects
				(font
					(size 1.27 1.27)
				)
				(justify mirror)
			)
		)
		(property "Value" ""
			(at 0 0 0)
			(layer "B.Fab")
			(effects
				(font
					(size 1.27 1.27)
				)
				(justify mirror)
			)
		)
		(duplicate_pad_numbers_are_jumpers no)
		(fp_line
			(start -0.7874 -0.4064)
			(end -0.7874 0.4064)
			(stroke
				(width 0.1524)
				(type default)
			)
			(layer "B.SilkS")
		)
		(fp_line
			(start -0.7874 0.4064)
			(end 0.7874 0.4064)
			(stroke
				(width 0.1524)
				(type default)
			)
			(layer "B.SilkS")
		)
		(fp_line
			(start 0.7874 -0.4064)
			(end -0.7874 -0.4064)
			(stroke
				(width 0.1524)
				(type default)
			)
			(layer "B.SilkS")
		)
		(fp_line
			(start 0.7874 0.4064)
			(end 0.7874 -0.4064)
			(stroke
				(width 0.1524)
				(type default)
			)
			(layer "B.SilkS")
		)
		(fp_line
			(start -0.67945 -0.3048)
			(end -0.67945 0.3048)
			(stroke
				(width 0.1)
				(type default)
			)
			(layer "B.Fab")
		)
		(fp_line
			(start -0.67945 0.3048)
			(end -0.120396 0.3048)
			(stroke
				(width 0.1)
				(type default)
			)
			(layer "B.Fab")
		)
		(fp_line
			(start -0.12065 -0.3048)
			(end -0.67945 -0.3048)
			(stroke
				(width 0.1)
				(type default)
			)
			(layer "B.Fab")
		)
		(fp_line
			(start -0.12065 -0.2794)
			(end -0.12065 -0.3048)
			(stroke
				(width 0.1)
				(type default)
			)
			(layer "B.Fab")
		)
		(fp_line
			(start -0.120396 0.2794)
			(end 0.12065 0.2794)
			(stroke
				(width 0.1)
				(type default)
			)
			(layer "B.Fab")
		)
		(fp_line
			(start -0.120396 0.3048)
			(end -0.120396 0.2794)
			(stroke
				(width 0.1)
				(type default)
			)
			(layer "B.Fab")
		)
		(fp_line
			(start 0.12065 -0.305054)
			(end 0.12065 -0.2794)
			(stroke
				(width 0.1)
				(type default)
			)
			(layer "B.Fab")
		)
		(fp_line
			(start 0.12065 -0.2794)
			(end -0.12065 -0.2794)
			(stroke
				(width 0.1)
				(type default)
			)
			(layer "B.Fab")
		)
		(fp_line
			(start 0.12065 0.2794)
			(end 0.12065 0.3048)
			(stroke
				(width 0.1)
				(type default)
			)
			(layer "B.Fab")
		)
		(fp_line
			(start 0.12065 0.3048)
			(end 0.67945 0.3048)
			(stroke
				(width 0.1)
				(type default)
			)
			(layer "B.Fab")
		)
		(fp_line
			(start 0.67945 -0.305054)
			(end 0.12065 -0.305054)
			(stroke
				(width 0.1)
				(type default)
			)
			(layer "B.Fab")
		)
		(fp_line
			(start 0.67945 0.3048)
			(end 0.67945 -0.305054)
			(stroke
				(width 0.1)
				(type default)
			)
			(layer "B.Fab")
		)
		(pad "1" smd circle
			(at 0.40005 0 180)
			(size 0 0)
			(layers "B.Cu" "B.Mask" "B.Paste")
			(net "SMB_S3M_CPU1_PIROM_3V3AUX_SCL")
		)
		(pad "2" smd circle
			(at -0.40005 0 180)
			(size 0 0)
			(layers "B.Cu" "B.Mask" "B.Paste")
			(net "SMB_S3M_CPU1_PIROM_3V3AUX_SCL_1")
		)
	)
)
